# SCM (Grand Teton) — schematic netlist excerpt (pin names and nets, part order shuffled) for the footprints in the layout excerpt that follows; sources: Cadence DE-HDL packaged netlist, KiCad conversion of 12092022_DA0F0TMDCD0_F0T_Management_Board_D_brd_V3_OCP.brd

R16  Q_RES  2.21K 1% EMPTY  pkg 0402LF  page 23 : A = V_BMC_LS_DDC_SCL_R ; B = CRT_VCC5
R636  Q_RES  0 5% CHIP  pkg 0402LF  page 22 : A = RST_EXTRST_N ; B = RST_BMC_EXTRST_R2_N

(kicad_pcb
	(version 20260206)
	(generator "pcbnew")
	(generator_version "10.0")
	(general
		(thickness 1.6)
		(legacy_teardrops no)
	)
	(paper "A4")
	(title_block
		(title "12092022_DA0F0TMDCD0_F0T_Management_Board_D_brd_V3_OCP.brd")
		(comment 1 "Grand Teton / footprints 54-55 of 1440")
	)
	(layers
		(0 "F.Cu" signal "TOP")
		(4 "In1.Cu" signal "GND")
		(6 "In2.Cu" signal "IN1")
		(8 "In3.Cu" signal "GND1")
		(10 "In4.Cu" signal "IN2")
		(12 "In5.Cu" signal "VCC")
		(14 "In6.Cu" signal "VCC1")
		(16 "In7.Cu" signal "IN3")
		(18 "In8.Cu" signal "GND2")
		(20 "In9.Cu" signal "IN4")
		(22 "In10.Cu" signal "GND3")
		(2 "B.Cu" signal "BOTTOM")
		(9 "F.Adhes" user "F.Adhesive")
		(11 "B.Adhes" user "B.Adhesive")
		(13 "F.Paste" user "Package Geometry/Pastemask Top")
		(15 "B.Paste" user "Package Geometry/Pastemask Bottom")
		(5 "F.SilkS" user "Ref Des/Silkscreen Top")
		(7 "B.SilkS" user "Ref Des/Silkscreen Bottom")
		(1 "F.Mask" user "Board Geometry/Soldermask Top")
		(3 "B.Mask" user "Board Geometry/Soldermask Bottom")
		(17 "Dwgs.User" user "User.Drawings")
		(19 "Cmts.User" user "User.Comments")
		(21 "Eco1.User" user "User.Eco1")
		(23 "Eco2.User" user "User.Eco2")
		(25 "Edge.Cuts" user "Board Geometry/Outline")
		(27 "Margin" user)
		(31 "F.CrtYd" user "Package Geometry/Place Bound Top")
		(29 "B.CrtYd" user "Package Geometry/Place Bound Bottom")
		(35 "F.Fab" user "Ref Des/Assembly Top")
		(33 "B.Fab" user "Ref Des/Assembly Bottom")
	)
	(footprint ""
		(layer "F.Cu")
		(at 54.229 -98.425 -90)
		(property "Reference" "R636"
			(at 0 0 270)
			(layer "F.SilkS")
			(hide yes)
			(effects
				(font
					(size 1.27 1.27)
				)
			)
		)
		(property "Value" ""
			(at 0 0 270)
			(layer "F.Fab")
			(effects
				(font
					(size 1.27 1.27)
				)
			)
		)
		(duplicate_pad_numbers_are_jumpers no)
		(fp_line
			(start -0.7874 0.4064)
			(end -0.7874 -0.4064)
			(stroke
				(width 0.1524)
				(type default)
			)
			(layer "F.SilkS")
		)
		(fp_line
			(start 0.7874 0.4064)
			(end -0.7874 0.4064)
			(stroke
				(width 0.1524)
				(type default)
			)
			(layer "F.SilkS")
		)
		(fp_line
			(start -0.7874 -0.4064)
			(end 0.7874 -0.4064)
			(stroke
				(width 0.1524)
				(type default)
			)
			(layer "F.SilkS")
		)
		(fp_line
			(start 0.7874 -0.4064)
			(end 0.7874 0.4064)
			(stroke
				(width 0.1524)
				(type default)
			)
			(layer "F.SilkS")
		)
		(fp_line
			(start -0.67945 0.3048)
			(end -0.67945 -0.305054)
			(stroke
				(width 0.1)
				(type default)
			)
			(layer "F.Fab")
		)
		(fp_line
			(start -0.12065 0.3048)
			(end -0.67945 0.3048)
			(stroke
				(width 0.1)
				(type default)
			)
			(layer "F.Fab")
		)
		(fp_line
			(start 0.120396 0.3048)
			(end 0.120396 0.2794)
			(stroke
				(width 0.1)
				(type default)
			)
			(layer "F.Fab")
		)
		(fp_line
			(start 0.67945 0.3048)
			(end 0.120396 0.3048)
			(stroke
				(width 0.1)
				(type default)
			)
			(layer "F.Fab")
		)
		(fp_line
			(start -0.12065 0.2794)
			(end -0.12065 0.3048)
			(stroke
				(width 0.1)
				(type default)
			)
			(layer "F.Fab")
		)
		(fp_line
			(start 0.120396 0.2794)
			(end -0.12065 0.2794)
			(stroke
				(width 0.1)
				(type default)
			)
			(layer "F.Fab")
		)
		(fp_line
			(start -0.12065 -0.2794)
			(end 0.12065 -0.2794)
			(stroke
				(width 0.1)
				(type default)
			)
			(layer "F.Fab")
		)
		(fp_line
			(start 0.12065 -0.2794)
			(end 0.12065 -0.3048)
			(stroke
				(width 0.1)
				(type default)
			)
			(layer "F.Fab")
		)
		(fp_line
			(start 0.12065 -0.3048)
			(end 0.67945 -0.3048)
			(stroke
				(width 0.1)
				(type default)
			)
			(layer "F.Fab")
		)
		(fp_line
			(start 0.67945 -0.3048)
			(end 0.67945 0.3048)
			(stroke
				(width 0.1)
				(type default)
			)
			(layer "F.Fab")
		)
		(fp_line
			(start -0.67945 -0.305054)
			(end -0.12065 -0.305054)
			(stroke
				(width 0.1)
				(type default)
			)
			(layer "F.Fab")
		)
		(fp_line
			(start -0.12065 -0.305054)
			(end -0.12065 -0.2794)
			(stroke
				(width 0.1)
				(type default)
			)
			(layer "F.Fab")
		)
		(pad "1" smd circle
			(at -0.40005 0 270)
			(size 0 0)
			(layers "F.Cu" "F.Mask" "F.Paste")
			(net "RST_EXTRST_N")
		)
		(pad "2" smd circle
			(at 0.40005 0 270)
			(size 0 0)
			(layers "F.Cu" "F.Mask" "F.Paste")
			(net "RST_BMC_EXTRST_R2_N")
		)
	)
	(footprint ""
		(layer "F.Cu")
		(at 29.6164 -25.908 180)
		(property "Reference" "R16"
			(at 0 0 180)
			(layer "F.SilkS")
			(hide yes)
			(effects
				(font
					(size 1.27 1.27)
				)
			)
		)
		(property "Value" ""
			(at 0 0 180)
			(layer "F.Fab")
			(effects
				(font
					(size 1.27 1.27)
				)
			)
		)
		(duplicate_pad_numbers_are_jumpers no)
		(fp_line
			(start 0.7874 0.4064)
			(end -0.7874 0.4064)
			(stroke
				(width 0.1524)
				(type default)
			)
			(layer "F.SilkS")
		)
		(fp_line
			(start 0.7874 -0.4064)
			(end 0.7874 0.4064)
			(stroke
				(width 0.1524)
				(type default)
			)
			(layer "F.SilkS")
		)
		(fp_line
			(start -0.7874 0.4064)
			(end -0.7874 -0.4064)
			(stroke
				(width 0.1524)
				(type default)
			)
			(layer "F.SilkS")
		)
		(fp_line
			(start -0.7874 -0.4064)
			(end 0.7874 -0.4064)
			(stroke
				(width 0.1524)
				(type default)
			)
			(layer "F.SilkS")
		)
		(fp_line
			(start 0.67945 0.3048)
			(end 0.120396 0.3048)
			(stroke
				(width 0.1)
				(type default)
			)
			(layer "F.Fab")
		)
		(fp_line
			(start 0.67945 -0.3048)
			(end 0.67945 0.3048)
			(stroke
				(width 0.1)
				(type default)
			)
			(layer "F.Fab")
		)
		(fp_line
			(start 0.12065 -0.2794)
			(end 0.12065 -0.3048)
			(stroke
				(width 0.1)
				(type default)
			)
			(layer "F.Fab")
		)
		(fp_line
			(start 0.12065 -0.3048)
			(end 0.67945 -0.3048)
			(stroke
				(width 0.1)
				(type default)
			)
			(layer "F.Fab")
		)
		(fp_line
			(start 0.120396 0.3048)
			(end 0.120396 0.2794)
			(stroke
				(width 0.1)
				(type default)
			)
			(layer "F.Fab")
		)
		(fp_line
			(start 0.120396 0.2794)
			(end -0.12065 0.2794)
			(stroke
				(width 0.1)
				(type default)
			)
			(layer "F.Fab")
		)
		(fp_line
			(start -0.12065 0.3048)
			(end -0.67945 0.3048)
			(stroke
				(width 0.1)
				(type default)
			)
			(layer "F.Fab")
		)
		(fp_line
			(start -0.12065 0.2794)
			(end -0.12065 0.3048)
			(stroke
				(width 0.1)
				(type default)
			)
			(layer "F.Fab")
		)
		(fp_line
			(start -0.12065 -0.2794)
			(end 0.12065 -0.2794)
			(stroke
				(width 0.1)
				(type default)
			)
			(layer "F.Fab")
		)
		(fp_line
			(start -0.12065 -0.305054)
			(end -0.12065 -0.2794)
			(stroke
				(width 0.1)
				(type default)
			)
			(layer "F.Fab")
		)
		(fp_line
			(start -0.67945 0.3048)
			(end -0.67945 -0.305054)
			(stroke
				(width 0.1)
				(type default)
			)
			(layer "F.Fab")
		)
		(fp_line
			(start -0.67945 -0.305054)
			(end -0.12065 -0.305054)
			(stroke
				(width 0.1)
				(type default)
			)
			(layer "F.Fab")
		)
		(pad "1" smd circle
			(at -0.40005 0 180)
			(size 0 0)
			(layers "F.Cu" "F.Mask" "F.Paste")
			(net "V_BMC_LS_DDC_SCL_R")
		)
		(pad "2" smd circle
			(at 0.40005 0 180)
			(size 0 0)
			(layers "F.Cu" "F.Mask" "F.Paste")
			(net "CRT_VCC5")
		)
	)
)
